(kicad_pcb
	(version 20260206)
	(generator "pcbnew")
	(generator_version "10.0")
	(general
		(thickness 1.6)
		(legacy_teardrops no)
	)
	(paper "A4")
	(title_block
		(title "v1-chassis-manager — T6M_CM_d_v01_1031_1645.brd")
		(comment 1 "Open CloudServer (Microsoft) / footprints 1508-1510 of 2512")
	)
	(layers
		(0 "F.Cu" signal "TOP")
		(4 "In1.Cu" signal "GND1")
		(6 "In2.Cu" signal "IN1")
		(8 "In3.Cu" signal "VCC1")
		(10 "In4.Cu" signal "VCC2")
		(12 "In5.Cu" signal "GND2")
		(14 "In6.Cu" signal "IN2")
		(16 "In7.Cu" signal "IN3")
		(18 "In8.Cu" signal "GND3")
		(2 "B.Cu" signal "BOTTOM")
		(9 "F.Adhes" user "F.Adhesive")
		(11 "B.Adhes" user "B.Adhesive")
		(13 "F.Paste" user "Package Geometry/Pastemask Top")
		(15 "B.Paste" user "Package Geometry/Pastemask Bottom")
		(5 "F.SilkS" user "Ref Des/Silkscreen Top")
		(7 "B.SilkS" user "Ref Des/Silkscreen Bottom")
		(1 "F.Mask" user "Board Geometry/Soldermask Top")
		(3 "B.Mask" user "Board Geometry/Soldermask Bottom")
		(17 "Dwgs.User" user "User.Drawings")
		(19 "Cmts.User" user "User.Comments")
		(21 "Eco1.User" user "User.Eco1")
		(23 "Eco2.User" user "User.Eco2")
		(25 "Edge.Cuts" user "Board Geometry/Outline")
		(27 "Margin" user)
		(31 "F.CrtYd" user "Package Geometry/Place Bound Top")
		(29 "B.CrtYd" user "Package Geometry/Place Bound Bottom")
		(35 "F.Fab" user "Ref Des/Assembly Top")
		(33 "B.Fab" user "Ref Des/Assembly Bottom")
	)
	(footprint ""
		(layer "F.Cu")
		(at 66.885566 -99.281234)
		(property "Reference" "R1090"
			(at 26.919174 54.04358 0)
			(unlocked yes)
			(layer "F.SilkS")
			(effects
				(font
					(size 0.7874 0.5842)
					(thickness 0.1524)
				)
				(justify left)
			)
		)
		(property "Value" ""
			(at 0 0 0)
			(layer "F.Fab")
			(effects
				(font
					(size 1.27 1.27)
				)
			)
		)
		(duplicate_pad_numbers_are_jumpers no)
		(fp_line
			(start -0.7874 -0.4064)
			(end 0.7874 -0.4064)
			(stroke
				(width 0.1524)
				(type default)
			)
			(layer "F.SilkS")
		)
		(fp_line
			(start -0.7874 0.4064)
			(end -0.7874 -0.4064)
			(stroke
				(width 0.1524)
				(type default)
			)
			(layer "F.SilkS")
		)
		(fp_line
			(start 0.7874 -0.4064)
			(end 0.7874 0.4064)
			(stroke
				(width 0.1524)
				(type default)
			)
			(layer "F.SilkS")
		)
		(fp_line
			(start 0.7874 0.4064)
			(end -0.7874 0.4064)
			(stroke
				(width 0.1524)
				(type default)
			)
			(layer "F.SilkS")
		)
		(fp_poly
			(pts
				(xy -0.508 0.2794) (xy -0.508 0.2286) (xy -0.635 0.2286) (xy -0.635 -0.254) (xy -0.5334 -0.254)
				(xy -0.5334 -0.2794) (xy 0.5334 -0.2794) (xy 0.5334 -0.254) (xy 0.635 -0.254) (xy 0.635 0.254) (xy 0.5334 0.254)
				(xy 0.5334 0.2794)
			)
			(stroke
				(width 0)
				(type default)
			)
			(fill no)
			(layer "F.CrtYd")
		)
		(pad "1" smd rect
			(at 0.40005 0)
			(size 0.4572 0.508)
			(layers "F.Cu" "F.Mask" "F.Paste")
			(net "P5V_STB_NODE1")
		)
		(pad "2" smd rect
			(at -0.40005 0)
			(size 0.4572 0.508)
			(layers "F.Cu" "F.Mask" "F.Paste")
			(net "FM_CPLD_NODE1_P1V8_SUS_EN_LV")
		)
	)
	(footprint ""
		(layer "F.Cu")
		(at 105.191814 -112.98682 180)
		(property "Reference" "PC120"
			(at 5.811774 -0.736092 0)
			(unlocked yes)
			(layer "F.SilkS")
			(effects
				(font
					(size 0.7874 0.5842)
					(thickness 0.1524)
				)
				(justify left)
			)
		)
		(property "Value" ""
			(at 0 0 180)
			(layer "F.Fab")
			(effects
				(font
					(size 1.27 1.27)
				)
			)
		)
		(duplicate_pad_numbers_are_jumpers no)
		(fp_line
			(start 1.905 0.8636)
			(end -1.905 0.8636)
			(stroke
				(width 0.1524)
				(type default)
			)
			(layer "F.SilkS")
		)
		(fp_line
			(start 1.905 -0.8636)
			(end 1.905 0.8636)
			(stroke
				(width 0.1524)
				(type default)
			)
			(layer "F.SilkS")
		)
		(fp_line
			(start 0 0.8382)
			(end 0 -0.8382)
			(stroke
				(width 0.1524)
				(type default)
			)
			(layer "F.SilkS")
		)
		(fp_line
			(start -1.905 0.8636)
			(end -1.905 -0.8636)
			(stroke
				(width 0.1524)
				(type default)
			)
			(layer "F.SilkS")
		)
		(fp_line
			(start -1.905 -0.8636)
			(end 1.905 -0.8636)
			(stroke
				(width 0.1524)
				(type default)
			)
			(layer "F.SilkS")
		)
		(fp_rect
			(start -1.524 0.7366)
			(end 1.524 -0.7366)
			(stroke
				(width 0)
				(type default)
			)
			(fill no)
			(layer "F.CrtYd")
		)
		(pad "1" smd rect
			(at 0.94996 0 180)
			(size 1.1176 1.3716)
			(layers "F.Cu" "F.Mask" "F.Paste")
			(net "GND")
		)
		(pad "2" smd rect
			(at -0.94996 0 180)
			(size 1.1176 1.3716)
			(layers "F.Cu" "F.Mask" "F.Paste")
			(net "PV_VCCP_NODE1")
		)
	)
	(footprint ""
		(layer "F.Cu")
		(at 175.000158 -182.749952)
		(property "Reference" "H6"
			(at -4.743958 -5.640578 0)
			(unlocked yes)
			(layer "F.SilkS")
			(effects
				(font
					(size 0.7874 0.5842)
					(thickness 0.1524)
				)
				(justify left)
			)
		)
		(property "Value" ""
			(at 0 0 0)
			(layer "F.Fab")
			(effects
				(font
					(size 1.27 1.27)
				)
			)
		)
		(duplicate_pad_numbers_are_jumpers no)
		(fp_poly
			(pts
				(arc
					(start 5.999988 4.99999)
					(mid 0 10.999978)
					(end -5.999988 4.99999)
				)
				(arc
					(start -5.999988 0)
					(mid 0 -5.999988)
					(end 5.999988 0)
				)
			)
			(stroke
				(width 0)
				(type default)
			)
			(fill no)
			(layer "B.CrtYd")
		)
		(fp_poly
			(pts
				(arc
					(start 5.999988 4.99999)
					(mid 0 10.999978)
					(end -5.999988 4.99999)
				)
				(arc
					(start -5.999988 0)
					(mid 0 -5.999988)
					(end 5.999988 0)
				)
			)
			(stroke
				(width 0)
				(type default)
			)
			(fill no)
			(layer "F.CrtYd")
		)
		(pad "" np_thru_hole circle
			(at 0 0)
			(size 3.81 3.81)
			(drill 3.81)
			(layers "*.Cu" "*.Mask")
			(clearance 0.381)
			(thermal_gap 0.381)
		)
	)
)
